G04 ================== begin FILE IDENTIFICATION RECORD ==================*
G04 Layout Name:  13919-sa.brd*
G04 Film Name:    BMASK*
G04 File Format:  Gerber RS274X*
G04 File Origin:  Cadence Allegro 16.5-S039*
G04 Origin Date:  Fri Nov 22 15:26:58 2013*
G04 *
G04 Layer:  VIA CLASS/SOLDERMASK_BOTTOM*
G04 Layer:  PIN/SOLDERMASK_BOTTOM*
G04 Layer:  PACKAGE GEOMETRY/SOLDERMASK_BOTTOM*
G04 Layer:  DRAWING FORMAT/LAYER_PCB_STORY*
G04 Layer:  DRAWING FORMAT/LAYER_SOLDER_B*
G04 Layer:  BOARD GEOMETRY/SOLDERMASK_BOTTOM*
G04 *
G04 Offset:    (0.00 0.00)*
G04 Mirror:    No*
G04 Mode:      Positive*
G04 Rotation:  0*
G04 FullContactRelief:  No*
G04 UndefLineWidth:     6.00*
G04 ================== end FILE IDENTIFICATION RECORD ====================*
%FSLAX35Y35*MOIN*%
%IR0*IPPOS*OFA0.00000B0.00000*MIA0B0*SFA1.00000B1.00000*%
%ADD11R,.028X.126*%
%ADD13C,.043*%
%ADD10R,.028X.165*%
%ADD12C,.093*%
%ADD14C,.086*%
%ADD15C,.02*%
%ADD16C,.006*%
G75*
%LPD*%
G75*
G36*
G01X20763Y-300D02*
X353253D01*
Y22012D01*
X20763D01*
Y-300D01*
G37*
G54D10*
X23622Y13762D03*
X31496D03*
X35433D03*
X39370D03*
X43307D03*
X47244D03*
X51181D03*
X55118D03*
X59055D03*
X62992D03*
X66929D03*
X70866D03*
X74803D03*
X78740D03*
X82677D03*
X86614D03*
X90551D03*
X94488D03*
X98425D03*
X102362D03*
X106299D03*
X110236D03*
X114173D03*
X118110D03*
X122047D03*
X125984D03*
X129921D03*
X133858D03*
X137795D03*
X141732D03*
X145669D03*
X149606D03*
X153543D03*
X161417D03*
X165354D03*
X169291D03*
X173228D03*
X177165D03*
X181102D03*
X185039D03*
X188976D03*
X192913D03*
X196850D03*
X200787D03*
X204724D03*
X208661D03*
X212598D03*
X216535D03*
X220472D03*
X228346D03*
X232283D03*
X236220D03*
X240157D03*
X244094D03*
X248031D03*
X251968D03*
X255905D03*
X259842D03*
X263779D03*
X267716D03*
X271653D03*
X275590D03*
X283464D03*
X287401D03*
X291338D03*
X311024D03*
X314961D03*
X318898D03*
X322835D03*
X326772D03*
X330709D03*
X334646D03*
X338583D03*
X342520D03*
X346457D03*
X350394D03*
X295275D03*
X299212D03*
G54D11*
X27559Y15712D03*
X157480D03*
X224409D03*
X279527D03*
G54D12*
X16538Y78346D03*
X304528D03*
G54D13*
X47243Y65551D03*
X43308Y73426D03*
X39373Y65551D03*
X35433Y73426D03*
X31498Y65551D03*
X27558Y73426D03*
X23623Y65551D03*
X47243Y91141D03*
X43308Y83266D03*
X39373Y91141D03*
X35433Y83266D03*
X31498Y91141D03*
X27558Y83266D03*
X23623Y91141D03*
X110238Y65551D03*
X106298Y73426D03*
X102363Y65551D03*
X98428Y73426D03*
X94488Y65551D03*
X90553Y73426D03*
X86613Y65551D03*
X82678Y73426D03*
X78743Y65551D03*
X74803Y73426D03*
X70868Y65551D03*
X66928Y73426D03*
X62993Y65551D03*
X59058Y73426D03*
X55118Y65551D03*
X51183Y73426D03*
X110238Y91141D03*
X106298Y83266D03*
X102363Y91141D03*
X98428Y83266D03*
X94488Y91141D03*
X90553Y83266D03*
X86613Y91141D03*
X82678Y83266D03*
X78743Y91141D03*
X74803Y83266D03*
X70868Y91141D03*
X66928Y83266D03*
X62993Y91141D03*
X59058Y83266D03*
X55118Y91141D03*
X51183Y83266D03*
X169293Y73426D03*
X165353Y65551D03*
X161418Y73426D03*
X157483Y65551D03*
X153543Y73426D03*
X149608Y65551D03*
X145668Y73426D03*
X141733Y65551D03*
X137798Y73426D03*
X133858Y65551D03*
X129923Y73426D03*
X125983Y65551D03*
X122048Y73426D03*
X118113Y65551D03*
X114173Y73426D03*
X169293Y83266D03*
X165353Y91141D03*
X161418Y83266D03*
X157483Y91141D03*
X153543Y83266D03*
X149608Y91141D03*
X145668Y83266D03*
X141733Y91141D03*
X137798Y83266D03*
X133858Y91141D03*
X129923Y83266D03*
X125983Y91141D03*
X122048Y83266D03*
X118113Y91141D03*
X114173Y83266D03*
X232283Y73426D03*
X228348Y65551D03*
X224408Y73426D03*
X220473Y65551D03*
X216538Y73426D03*
X212598Y65551D03*
X208663Y73426D03*
X204723Y65551D03*
X200788Y73426D03*
X196853Y65551D03*
X192913Y73426D03*
X188978Y65551D03*
X185038Y73426D03*
X181103Y65551D03*
X177168Y73426D03*
X173228Y65551D03*
X232283Y83266D03*
X228348Y91141D03*
X224408Y83266D03*
X220473Y91141D03*
X216538Y83266D03*
X212598Y91141D03*
X208663Y83266D03*
X204723Y91141D03*
X200788Y83266D03*
X196853Y91141D03*
X192913Y83266D03*
X188978Y91141D03*
X185038Y83266D03*
X181103Y91141D03*
X177168Y83266D03*
X173228Y91141D03*
X291338Y65551D03*
X287403Y73426D03*
X283463Y65551D03*
X279528Y73426D03*
X275593Y65551D03*
X271653Y73426D03*
X267718Y65551D03*
X263778Y73426D03*
X259843Y65551D03*
X255908Y73426D03*
X251968Y65551D03*
X248033Y73426D03*
X244093Y65551D03*
X240158Y73426D03*
X236223Y65551D03*
X291338Y91141D03*
X287403Y83266D03*
X283463Y91141D03*
X279528Y83266D03*
X275593Y91141D03*
X271653Y83266D03*
X267718Y91141D03*
X263778Y83266D03*
X259843Y91141D03*
X255908Y83266D03*
X251968Y91141D03*
X248033Y83266D03*
X244093Y91141D03*
X240158Y83266D03*
X236223Y91141D03*
X350393Y73426D03*
X346458Y65551D03*
X342518Y73426D03*
X338583Y65551D03*
X334648Y73426D03*
X330708Y65551D03*
X326773Y73426D03*
X322833Y65551D03*
X318898Y73426D03*
X314963Y65551D03*
X311023Y73426D03*
X299213Y65551D03*
X295278Y73426D03*
X350393Y83266D03*
X346458Y91141D03*
X342518Y83266D03*
X338583Y91141D03*
X334648Y83266D03*
X330708Y91141D03*
X326773Y83266D03*
X322833Y91141D03*
X318898Y83266D03*
X314963Y91141D03*
X311023Y83266D03*
X299213Y91141D03*
X295278Y83266D03*
G54D14*
X8950Y97440D03*
X8750Y50860D03*
X-2462Y651994D03*
X364570Y96910D03*
X758452Y17317D03*
X755722Y677788D03*
G54D15*
G01X-67189Y-77263D02*
G02I-12000J0D01*
G01X-72339D02*
G02I-6850J0D01*
G01X-79189Y-93263D02*
Y-61263D01*
G01X-63189Y-77263D02*
X-95189D01*
G01X-63189Y-93263D02*
Y-173263D01*
G01D02*
X1156611D01*
G01X-63189Y-93263D02*
X1156611D01*
G01X-63189Y-128763D02*
X1156611D01*
G01X369111Y-93263D02*
Y-173263D01*
G01X506611Y-93263D02*
Y-173263D01*
G01X621611Y-93263D02*
Y-173263D01*
G01X789111Y-93263D02*
Y-173263D01*
G01X959111Y-93263D02*
Y-173263D01*
G01X1156611Y-93263D02*
Y-173263D01*
G01X1184611Y-77263D02*
G02I-12000J0D01*
G01X1179461D02*
G02I-6850J0D01*
G01X1172611Y-93263D02*
Y-61263D01*
G01X1188611Y-77263D02*
X1156611D01*
G54D16*
G01X-44374Y-163263D02*
Y-145763D01*
G01X-35204D02*
Y-163263D01*
G01Y-154513D02*
X-44374D01*
G01X-22289Y-163263D02*
X-23599Y-162971D01*
X-24909Y-161805D01*
X-25783Y-159763D01*
X-26219Y-157430D01*
X-25783Y-155096D01*
X-24909Y-153055D01*
X-23599Y-151888D01*
X-22289Y-151597D01*
X-20979Y-151888D01*
X-19669Y-153055D01*
X-18796Y-155096D01*
X-18577Y-157430D01*
X-18796Y-159763D01*
X-19669Y-161805D01*
X-20979Y-162971D01*
X-22289Y-163263D01*
G01X-8501D02*
Y-151597D01*
G01Y-154513D02*
X-7627Y-153055D01*
X-6317Y-151888D01*
X-4571Y-151597D01*
X-3043Y-151888D01*
X-1732Y-153055D01*
X-1077Y-155096D01*
Y-163263D01*
G01X9436Y-155388D02*
X16423D01*
X15768Y-153346D01*
X14676Y-152180D01*
X13148Y-151597D01*
X11619Y-151888D01*
X10309Y-152763D01*
X9436Y-154805D01*
X8999Y-156555D01*
Y-158305D01*
X9436Y-160055D01*
X10528Y-161805D01*
X11838Y-162971D01*
X13366Y-163263D01*
X14894Y-162680D01*
X16423Y-160930D01*
G01X25626Y-168513D02*
X26936Y-169096D01*
X28683Y-168513D01*
X29774Y-167347D01*
X30648Y-165888D01*
X31957Y-161222D01*
X34796Y-151597D01*
G01X27809D02*
X31957Y-161222D01*
G01X66957Y-153930D02*
X67831Y-153055D01*
X68486Y-151597D01*
X68923Y-149554D01*
X68486Y-147805D01*
X67613Y-146638D01*
X66084Y-145763D01*
X60189D01*
Y-163263D01*
X67394D01*
X68923Y-162097D01*
X69796Y-160346D01*
X70233Y-158305D01*
X69796Y-156263D01*
X68486Y-154513D01*
X66957Y-153930D01*
X60189D01*
G01X86641Y-163263D02*
Y-151597D01*
G01Y-153638D02*
X85768Y-152472D01*
X84457Y-151888D01*
X82929Y-151597D01*
X81401Y-152180D01*
X80091Y-153346D01*
X79217Y-155096D01*
X78781Y-157430D01*
X79217Y-159763D01*
X80091Y-161513D01*
X81401Y-162680D01*
X82929Y-163263D01*
X84457Y-162971D01*
X85768Y-162097D01*
X86641Y-160930D01*
G01X104141Y-145763D02*
Y-163263D01*
G01Y-160639D02*
X103268Y-162097D01*
X101957Y-162971D01*
X100429Y-163263D01*
X98683Y-162680D01*
X97373Y-161222D01*
X96499Y-159472D01*
X96281Y-157430D01*
X96499Y-155388D01*
X97373Y-153638D01*
X98683Y-152180D01*
X100429Y-151597D01*
X101957Y-151888D01*
X103049Y-152472D01*
X104141Y-153638D01*
G01X114654Y-167638D02*
X116183Y-168805D01*
X117929Y-169096D01*
X119457Y-168805D01*
X120768Y-167347D01*
X121641Y-165305D01*
Y-151597D01*
G01Y-153930D02*
X120768Y-152763D01*
X119457Y-151888D01*
X117929Y-151597D01*
X116183Y-152180D01*
X115091Y-153346D01*
X114217Y-155388D01*
X113781Y-157430D01*
X113999Y-159180D01*
X114873Y-161222D01*
X116183Y-162680D01*
X117929Y-163263D01*
X119239Y-162971D01*
X120768Y-161805D01*
X121641Y-160639D01*
G01X131936Y-155388D02*
X138923D01*
X138268Y-153346D01*
X137176Y-152180D01*
X135648Y-151597D01*
X134119Y-151888D01*
X132809Y-152763D01*
X131936Y-154805D01*
X131499Y-156555D01*
Y-158305D01*
X131936Y-160055D01*
X133028Y-161805D01*
X134338Y-162971D01*
X135866Y-163263D01*
X137394Y-162680D01*
X138923Y-160930D01*
G01X149654Y-163263D02*
Y-151597D01*
G01Y-153930D02*
X150746Y-152763D01*
X151838Y-151888D01*
X153366Y-151597D01*
X154457Y-151888D01*
X155768Y-152763D01*
G01X183344Y-163263D02*
Y-145763D01*
X188803D01*
X190549Y-146638D01*
X191641Y-147805D01*
X192078Y-150138D01*
X191641Y-152472D01*
X190331Y-153930D01*
X188803Y-154805D01*
X183344D01*
G01X188803D02*
X192078Y-163263D01*
G01X205211Y-151597D02*
Y-163263D01*
G01Y-146930D02*
X204774Y-146638D01*
Y-146055D01*
X205211Y-145763D01*
X205648Y-146055D01*
Y-146638D01*
X205211Y-146930D01*
G01X219436Y-161222D02*
X220528Y-162388D01*
X222056Y-163263D01*
X223366D01*
X224676Y-162680D01*
X225549Y-161805D01*
X225986Y-160639D01*
X225768Y-158888D01*
X224894Y-158013D01*
X220964Y-156263D01*
X220091Y-154221D01*
X220528Y-152763D01*
X221401Y-151888D01*
X222711Y-151597D01*
X224021Y-151888D01*
X225331Y-152763D01*
G01X236936Y-155388D02*
X243923D01*
X243268Y-153346D01*
X242176Y-152180D01*
X240648Y-151597D01*
X239119Y-151888D01*
X237809Y-152763D01*
X236936Y-154805D01*
X236499Y-156555D01*
Y-158305D01*
X236936Y-160055D01*
X238028Y-161805D01*
X239338Y-162971D01*
X240866Y-163263D01*
X242394Y-162680D01*
X243923Y-160930D01*
G01X254654Y-163263D02*
Y-151597D01*
G01Y-153930D02*
X255746Y-152763D01*
X256838Y-151888D01*
X258366Y-151597D01*
X259457Y-151888D01*
X260768Y-152763D01*
G01X297514Y-147222D02*
X296204Y-146346D01*
X294676Y-145763D01*
X292929D01*
X290964Y-146638D01*
X289436Y-148096D01*
X288344Y-149847D01*
X287471Y-152763D01*
X287252Y-155388D01*
X287689Y-158013D01*
X288344Y-159763D01*
X289654Y-161513D01*
X291183Y-162680D01*
X292711Y-163263D01*
X294239D01*
X295768Y-162680D01*
X297078Y-161805D01*
X298170Y-160639D01*
G01X314141Y-163263D02*
Y-151597D01*
G01Y-153638D02*
X313268Y-152472D01*
X311957Y-151888D01*
X310429Y-151597D01*
X308901Y-152180D01*
X307591Y-153346D01*
X306717Y-155096D01*
X306281Y-157430D01*
X306717Y-159763D01*
X307591Y-161513D01*
X308901Y-162680D01*
X310429Y-163263D01*
X311957Y-162971D01*
X313268Y-162097D01*
X314141Y-160930D01*
G01X324654Y-163263D02*
Y-151597D01*
G01Y-153930D02*
X325746Y-152763D01*
X326838Y-151888D01*
X328366Y-151597D01*
X329457Y-151888D01*
X330768Y-152763D01*
G01X349141Y-145763D02*
Y-163263D01*
G01Y-160639D02*
X348268Y-162097D01*
X346957Y-162971D01*
X345429Y-163263D01*
X343683Y-162680D01*
X342373Y-161222D01*
X341499Y-159472D01*
X341281Y-157430D01*
X341499Y-155388D01*
X342373Y-153638D01*
X343683Y-152180D01*
X345429Y-151597D01*
X346957Y-151888D01*
X348049Y-152472D01*
X349141Y-153638D01*
G01X112034Y-118263D02*
Y-100763D01*
X117711Y-115346D01*
X123388Y-100763D01*
Y-118263D01*
G01X135211D02*
X133901Y-117971D01*
X132591Y-116805D01*
X131717Y-114763D01*
X131281Y-112430D01*
X131717Y-110096D01*
X132591Y-108055D01*
X133901Y-106888D01*
X135211Y-106597D01*
X136521Y-106888D01*
X137831Y-108055D01*
X138704Y-110096D01*
X138923Y-112430D01*
X138704Y-114763D01*
X137831Y-116805D01*
X136521Y-117971D01*
X135211Y-118263D01*
G01X156641Y-100763D02*
Y-118263D01*
G01Y-115639D02*
X155768Y-117097D01*
X154457Y-117971D01*
X152929Y-118263D01*
X151183Y-117680D01*
X149873Y-116222D01*
X148999Y-114472D01*
X148781Y-112430D01*
X148999Y-110388D01*
X149873Y-108638D01*
X151183Y-107180D01*
X152929Y-106597D01*
X154457Y-106888D01*
X155549Y-107472D01*
X156641Y-108638D01*
G01X166936Y-110388D02*
X173923D01*
X173268Y-108346D01*
X172176Y-107180D01*
X170648Y-106597D01*
X169119Y-106888D01*
X167809Y-107763D01*
X166936Y-109805D01*
X166499Y-111555D01*
Y-113305D01*
X166936Y-115055D01*
X168028Y-116805D01*
X169338Y-117971D01*
X170866Y-118263D01*
X172394Y-117680D01*
X173923Y-115930D01*
G01X187711Y-118263D02*
Y-100763D01*
G01X402811Y-163263D02*
Y-145763D01*
X400191Y-149263D01*
G01Y-163263D02*
X405431D01*
G01X415508Y-159763D02*
X416817Y-161805D01*
X418564Y-162971D01*
X420529Y-163263D01*
X422276Y-162971D01*
X424023Y-161513D01*
X425114Y-159763D01*
X425333Y-158013D01*
X424896Y-155972D01*
X423368Y-154513D01*
X421839Y-153930D01*
X419874D01*
G01X421839D02*
X423149Y-153055D01*
X424241Y-151597D01*
X424678Y-149847D01*
X424241Y-148096D01*
X423149Y-146638D01*
X421184Y-145763D01*
X419219Y-146055D01*
X417254Y-147222D01*
G01X434099Y-161222D02*
X435628Y-162680D01*
X437374Y-163263D01*
X439121Y-162680D01*
X440649Y-160930D01*
X441741Y-158305D01*
X442178Y-155680D01*
Y-152472D01*
X441741Y-149847D01*
X440649Y-147513D01*
X439339Y-146346D01*
X437811Y-145763D01*
X436064Y-146346D01*
X434754Y-147513D01*
X433881Y-149263D01*
X433444Y-151597D01*
X433881Y-153638D01*
X434973Y-155680D01*
X436283Y-156847D01*
X437811Y-157138D01*
X439557Y-156555D01*
X440868Y-155096D01*
X442178Y-152472D01*
G01X455311Y-163263D02*
Y-145763D01*
X452691Y-149263D01*
G01Y-163263D02*
X457931D01*
G01X469099Y-161222D02*
X470628Y-162680D01*
X472374Y-163263D01*
X474121Y-162680D01*
X475649Y-160930D01*
X476741Y-158305D01*
X477178Y-155680D01*
Y-152472D01*
X476741Y-149847D01*
X475649Y-147513D01*
X474339Y-146346D01*
X472811Y-145763D01*
X471064Y-146346D01*
X469754Y-147513D01*
X468881Y-149263D01*
X468444Y-151597D01*
X468881Y-153638D01*
X469973Y-155680D01*
X471283Y-156847D01*
X472811Y-157138D01*
X474557Y-156555D01*
X475868Y-155096D01*
X477178Y-152472D01*
G01X389694Y-118263D02*
Y-100763D01*
X394934D01*
X396681Y-101638D01*
X397991Y-103680D01*
X398428Y-106013D01*
X397991Y-108346D01*
X396899Y-110096D01*
X394934Y-110972D01*
X389694D01*
G01X416364Y-102222D02*
X415054Y-101346D01*
X413526Y-100763D01*
X411779D01*
X409814Y-101638D01*
X408286Y-103096D01*
X407194Y-104847D01*
X406321Y-107763D01*
X406102Y-110388D01*
X406539Y-113013D01*
X407194Y-114763D01*
X408504Y-116513D01*
X410033Y-117680D01*
X411561Y-118263D01*
X413089D01*
X414618Y-117680D01*
X415928Y-116805D01*
X417020Y-115639D01*
G01X430807Y-108930D02*
X431681Y-108055D01*
X432336Y-106597D01*
X432773Y-104554D01*
X432336Y-102805D01*
X431463Y-101638D01*
X429934Y-100763D01*
X424039D01*
Y-118263D01*
X431244D01*
X432773Y-117097D01*
X433646Y-115346D01*
X434083Y-113305D01*
X433646Y-111263D01*
X432336Y-109513D01*
X430807Y-108930D01*
X424039D01*
G01X440011Y-124096D02*
X453111D01*
G01X459039Y-118263D02*
Y-100763D01*
X469083Y-118263D01*
Y-100763D01*
G01X481561Y-118263D02*
X479814Y-117971D01*
X478286Y-116805D01*
X476976Y-115055D01*
X476102Y-113013D01*
X475666Y-110680D01*
Y-108346D01*
X476102Y-106013D01*
X476976Y-103971D01*
X478286Y-102222D01*
X479814Y-101055D01*
X481561Y-100763D01*
X483307Y-101055D01*
X484836Y-102222D01*
X486146Y-103971D01*
X487020Y-106013D01*
X487456Y-108346D01*
Y-110680D01*
X487020Y-113013D01*
X486146Y-115055D01*
X484836Y-116805D01*
X483307Y-117971D01*
X481561Y-118263D01*
G01X532402Y-100763D02*
X537861Y-118263D01*
X543320Y-100763D01*
G01X559728Y-118263D02*
X550994D01*
Y-100763D01*
X559728D01*
G01X556234Y-109221D02*
X550994D01*
G01X568494Y-118263D02*
Y-100763D01*
X573953D01*
X575699Y-101638D01*
X576791Y-102805D01*
X577228Y-105138D01*
X576791Y-107472D01*
X575481Y-108930D01*
X573953Y-109805D01*
X568494D01*
G01X573953D02*
X577228Y-118263D01*
G01X590361Y-118846D02*
X589924Y-118555D01*
Y-117971D01*
X590361Y-117680D01*
X590798Y-117971D01*
Y-118555D01*
X590361Y-118846D01*
G01X550776Y-160930D02*
X552523Y-162388D01*
X554488Y-163263D01*
X556234D01*
X557981Y-162388D01*
X559291Y-160930D01*
X559946Y-158888D01*
X559509Y-156847D01*
X558418Y-155096D01*
X556453Y-153930D01*
X553833Y-153346D01*
X552304Y-152180D01*
X551649Y-150138D01*
X552086Y-148096D01*
X553178Y-146638D01*
X554706Y-145763D01*
X556234D01*
X557763Y-146346D01*
X559073Y-147805D01*
G01X567402Y-163263D02*
X572861Y-145763D01*
X578320Y-163263D01*
G01X576354Y-157138D02*
X569367D01*
G01X738565Y-153930D02*
X737691Y-153055D01*
X737036Y-151597D01*
X736599Y-149554D01*
X737036Y-147805D01*
X737909Y-146638D01*
X739438Y-145763D01*
X745333D01*
Y-163263D01*
X738128D01*
X736599Y-162097D01*
X735726Y-160346D01*
X735289Y-158305D01*
X735726Y-156263D01*
X737036Y-154513D01*
X738565Y-153930D01*
X745333D01*
G01X728488Y-163263D02*
Y-145763D01*
X722811Y-160346D01*
X717134Y-145763D01*
Y-163263D01*
G01X710770D02*
X705311Y-145763D01*
X699852Y-163263D01*
G01X701818Y-157138D02*
X708805D01*
G01X692396Y-160930D02*
X690649Y-162388D01*
X688684Y-163263D01*
X686938D01*
X685191Y-162388D01*
X683881Y-160930D01*
X683226Y-158888D01*
X683663Y-156847D01*
X684754Y-155096D01*
X686719Y-153930D01*
X689339Y-153346D01*
X690868Y-152180D01*
X691523Y-150138D01*
X691086Y-148096D01*
X689994Y-146638D01*
X688466Y-145763D01*
X686938D01*
X685409Y-146346D01*
X684099Y-147805D01*
G01X675114Y-163263D02*
Y-145763D01*
G01X666818D02*
X675114Y-156555D01*
G01X665508Y-163263D02*
X671403Y-151597D01*
G01X665944Y-100763D02*
Y-118263D01*
X674678D01*
G01X691741D02*
Y-106597D01*
G01Y-108638D02*
X690868Y-107472D01*
X689557Y-106888D01*
X688029Y-106597D01*
X686501Y-107180D01*
X685191Y-108346D01*
X684317Y-110096D01*
X683881Y-112430D01*
X684317Y-114763D01*
X685191Y-116513D01*
X686501Y-117680D01*
X688029Y-118263D01*
X689557Y-117971D01*
X690868Y-117097D01*
X691741Y-115930D01*
G01X700726Y-123513D02*
X702036Y-124096D01*
X703783Y-123513D01*
X704874Y-122347D01*
X705748Y-120888D01*
X707057Y-116222D01*
X709896Y-106597D01*
G01X702909D02*
X707057Y-116222D01*
G01X719536Y-110388D02*
X726523D01*
X725868Y-108346D01*
X724776Y-107180D01*
X723248Y-106597D01*
X721719Y-106888D01*
X720409Y-107763D01*
X719536Y-109805D01*
X719099Y-111555D01*
Y-113305D01*
X719536Y-115055D01*
X720628Y-116805D01*
X721938Y-117971D01*
X723466Y-118263D01*
X724994Y-117680D01*
X726523Y-115930D01*
G01X737254Y-118263D02*
Y-106597D01*
G01Y-108930D02*
X738346Y-107763D01*
X739438Y-106888D01*
X740966Y-106597D01*
X742057Y-106888D01*
X743368Y-107763D01*
G01X808058Y-118263D02*
Y-100763D01*
X812424D01*
X814171Y-101638D01*
X815481Y-102805D01*
X816573Y-104554D01*
X817446Y-106597D01*
X817664Y-109513D01*
X817446Y-112430D01*
X816573Y-114472D01*
X815481Y-116222D01*
X814171Y-117388D01*
X812424Y-118263D01*
X808058D01*
G01X827086Y-110388D02*
X834073D01*
X833418Y-108346D01*
X832326Y-107180D01*
X830798Y-106597D01*
X829269Y-106888D01*
X827959Y-107763D01*
X827086Y-109805D01*
X826649Y-111555D01*
Y-113305D01*
X827086Y-115055D01*
X828178Y-116805D01*
X829488Y-117971D01*
X831016Y-118263D01*
X832544Y-117680D01*
X834073Y-115930D01*
G01X844586Y-116222D02*
X845678Y-117388D01*
X847206Y-118263D01*
X848516D01*
X849826Y-117680D01*
X850699Y-116805D01*
X851136Y-115639D01*
X850918Y-113888D01*
X850044Y-113013D01*
X846114Y-111263D01*
X845241Y-109221D01*
X845678Y-107763D01*
X846551Y-106888D01*
X847861Y-106597D01*
X849171Y-106888D01*
X850481Y-107763D01*
G01X865361Y-106597D02*
Y-118263D01*
G01Y-101930D02*
X864924Y-101638D01*
Y-101055D01*
X865361Y-100763D01*
X865798Y-101055D01*
Y-101638D01*
X865361Y-101930D01*
G01X879804Y-122638D02*
X881333Y-123805D01*
X883079Y-124096D01*
X884607Y-123805D01*
X885918Y-122347D01*
X886791Y-120305D01*
Y-106597D01*
G01Y-108930D02*
X885918Y-107763D01*
X884607Y-106888D01*
X883079Y-106597D01*
X881333Y-107180D01*
X880241Y-108346D01*
X879367Y-110388D01*
X878931Y-112430D01*
X879149Y-114180D01*
X880023Y-116222D01*
X881333Y-117680D01*
X883079Y-118263D01*
X884389Y-117971D01*
X885918Y-116805D01*
X886791Y-115639D01*
G01X896649Y-118263D02*
Y-106597D01*
G01Y-109513D02*
X897523Y-108055D01*
X898833Y-106888D01*
X900579Y-106597D01*
X902107Y-106888D01*
X903418Y-108055D01*
X904073Y-110096D01*
Y-118263D01*
G01X914586Y-110388D02*
X921573D01*
X920918Y-108346D01*
X919826Y-107180D01*
X918298Y-106597D01*
X916769Y-106888D01*
X915459Y-107763D01*
X914586Y-109805D01*
X914149Y-111555D01*
Y-113305D01*
X914586Y-115055D01*
X915678Y-116805D01*
X916988Y-117971D01*
X918516Y-118263D01*
X920044Y-117680D01*
X921573Y-115930D01*
G01X932304Y-118263D02*
Y-106597D01*
G01Y-108930D02*
X933396Y-107763D01*
X934488Y-106888D01*
X936016Y-106597D01*
X937107Y-106888D01*
X938418Y-107763D01*
G01X853991Y-145763D02*
X859231D01*
G01X856611D02*
Y-163263D01*
G01X853991D02*
X859231D01*
G01X868652Y-145763D02*
X874111Y-163263D01*
X879570Y-145763D01*
G01X891611Y-163263D02*
Y-155388D01*
X887244Y-145763D01*
G01X895978D02*
X891611Y-155388D01*
G01X979061Y-163263D02*
Y-145763D01*
X976441Y-149263D01*
G01Y-163263D02*
X981681D01*
G01X996561D02*
Y-145763D01*
X993941Y-149263D01*
G01Y-163263D02*
X999181D01*
G01X1010131Y-163846D02*
X1017991Y-145763D01*
G01X1027413Y-148680D02*
X1028723Y-146930D01*
X1030251Y-146055D01*
X1031998Y-145763D01*
X1034181Y-146346D01*
X1035709Y-147805D01*
X1036146Y-149554D01*
X1035928Y-151305D01*
X1035054Y-152763D01*
X1030688Y-155680D01*
X1028723Y-157721D01*
X1027413Y-160639D01*
X1026976Y-163263D01*
X1036146D01*
G01X1044913Y-148680D02*
X1046223Y-146930D01*
X1047751Y-146055D01*
X1049498Y-145763D01*
X1051681Y-146346D01*
X1053209Y-147805D01*
X1053646Y-149554D01*
X1053428Y-151305D01*
X1052554Y-152763D01*
X1048188Y-155680D01*
X1046223Y-157721D01*
X1044913Y-160639D01*
X1044476Y-163263D01*
X1053646D01*
G01X1062631Y-163846D02*
X1070491Y-145763D01*
G01X1079913Y-148680D02*
X1081223Y-146930D01*
X1082751Y-146055D01*
X1084498Y-145763D01*
X1086681Y-146346D01*
X1088209Y-147805D01*
X1088646Y-149554D01*
X1088428Y-151305D01*
X1087554Y-152763D01*
X1083188Y-155680D01*
X1081223Y-157721D01*
X1079913Y-160639D01*
X1079476Y-163263D01*
X1088646D01*
G01X1101561Y-145763D02*
X1099814Y-146346D01*
X1098504Y-147805D01*
X1097631Y-149554D01*
X1096976Y-151888D01*
X1096758Y-154513D01*
X1096976Y-157138D01*
X1097631Y-159472D01*
X1098504Y-161222D01*
X1099814Y-162680D01*
X1101561Y-163263D01*
X1103307Y-162680D01*
X1104618Y-161222D01*
X1105491Y-159472D01*
X1106146Y-157138D01*
X1106364Y-154513D01*
X1106146Y-151888D01*
X1105491Y-149554D01*
X1104618Y-147805D01*
X1103307Y-146346D01*
X1101561Y-145763D01*
G01X1119061Y-163263D02*
Y-145763D01*
X1116441Y-149263D01*
G01Y-163263D02*
X1121681D01*
G01X1131758Y-159763D02*
X1133067Y-161805D01*
X1134814Y-162971D01*
X1136779Y-163263D01*
X1138526Y-162971D01*
X1140273Y-161513D01*
X1141364Y-159763D01*
X1141583Y-158013D01*
X1141146Y-155972D01*
X1139618Y-154513D01*
X1138089Y-153930D01*
X1136124D01*
G01X1138089D02*
X1139399Y-153055D01*
X1140491Y-151597D01*
X1140928Y-149847D01*
X1140491Y-148096D01*
X1139399Y-146638D01*
X1137434Y-145763D01*
X1135469Y-146055D01*
X1133504Y-147222D01*
G01X1026758Y-118263D02*
Y-100763D01*
X1031124D01*
X1032871Y-101638D01*
X1034181Y-102805D01*
X1035273Y-104554D01*
X1036146Y-106597D01*
X1036364Y-109513D01*
X1036146Y-112430D01*
X1035273Y-114472D01*
X1034181Y-116222D01*
X1032871Y-117388D01*
X1031124Y-118263D01*
X1026758D01*
G01X1052991D02*
Y-106597D01*
G01Y-108638D02*
X1052118Y-107472D01*
X1050807Y-106888D01*
X1049279Y-106597D01*
X1047751Y-107180D01*
X1046441Y-108346D01*
X1045567Y-110096D01*
X1045131Y-112430D01*
X1045567Y-114763D01*
X1046441Y-116513D01*
X1047751Y-117680D01*
X1049279Y-118263D01*
X1050807Y-117971D01*
X1052118Y-117097D01*
X1052991Y-115930D01*
G01X1066561Y-100763D02*
Y-118263D01*
G01X1063504Y-106597D02*
X1069618D01*
G01X1080786Y-110388D02*
X1087773D01*
X1087118Y-108346D01*
X1086026Y-107180D01*
X1084498Y-106597D01*
X1082969Y-106888D01*
X1081659Y-107763D01*
X1080786Y-109805D01*
X1080349Y-111555D01*
Y-113305D01*
X1080786Y-115055D01*
X1081878Y-116805D01*
X1083188Y-117971D01*
X1084716Y-118263D01*
X1086244Y-117680D01*
X1087773Y-115930D01*
M02*
